(kicad_pcb
	(version 20260206)
	(generator "pcbnew")
	(generator_version "10.0")
	(general
		(thickness 1.6)
		(legacy_teardrops no)
	)
	(paper "A4")
	(title_block
		(title "03242023_DA0F0TMBIJ0_F0T_Motherboard_J_brd_V01_OCP.brd")
		(comment 1 "Grand Teton / footprints 4521-4527 of 6105")
	)
	(layers
		(0 "F.Cu" signal "TOP")
		(4 "In1.Cu" signal "GND")
		(6 "In2.Cu" signal "IN1")
		(8 "In3.Cu" signal "GND1")
		(10 "In4.Cu" signal "IN2")
		(12 "In5.Cu" signal "GND2")
		(14 "In6.Cu" signal "IN3")
		(16 "In7.Cu" signal "GND3")
		(18 "In8.Cu" signal "VCC")
		(20 "In9.Cu" signal "VCC1")
		(22 "In10.Cu" signal "GND4")
		(24 "In11.Cu" signal "IN4")
		(26 "In12.Cu" signal "GND5")
		(28 "In13.Cu" signal "IN5")
		(30 "In14.Cu" signal "GND6")
		(32 "In15.Cu" signal "IN6")
		(34 "In16.Cu" signal "GND7")
		(2 "B.Cu" signal "BOTTOM")
		(9 "F.Adhes" user "F.Adhesive")
		(11 "B.Adhes" user "B.Adhesive")
		(13 "F.Paste" user "Package Geometry/Pastemask Top")
		(15 "B.Paste" user "Package Geometry/Pastemask Bottom")
		(5 "F.SilkS" user "Ref Des/Silkscreen Top")
		(7 "B.SilkS" user "Ref Des/Silkscreen Bottom")
		(1 "F.Mask" user "Board Geometry/Soldermask Top")
		(3 "B.Mask" user "Board Geometry/Soldermask Bottom")
		(17 "Dwgs.User" user "User.Drawings")
		(19 "Cmts.User" user "User.Comments")
		(21 "Eco1.User" user "User.Eco1")
		(23 "Eco2.User" user "User.Eco2")
		(25 "Edge.Cuts" user "Board Geometry/Outline")
		(27 "Margin" user)
		(31 "F.CrtYd" user "Package Geometry/Place Bound Top")
		(29 "B.CrtYd" user "Package Geometry/Place Bound Bottom")
		(35 "F.Fab" user "Ref Des/Assembly Top")
		(33 "B.Fab" user "Ref Des/Assembly Bottom")
	)
	(footprint ""
		(layer "B.Cu")
		(at 252.222 -99.405948 180)
		(property "Reference" "C120"
			(at 0 0 0)
			(layer "B.SilkS")
			(hide yes)
			(effects
				(font
					(size 1.27 1.27)
				)
				(justify mirror)
			)
		)
		(property "Value" ""
			(at 0 0 0)
			(layer "B.Fab")
			(effects
				(font
					(size 1.27 1.27)
				)
				(justify mirror)
			)
		)
		(duplicate_pad_numbers_are_jumpers no)
		(fp_line
			(start 0.7874 0.4064)
			(end 0.7874 -0.4064)
			(stroke
				(width 0.1524)
				(type default)
			)
			(layer "B.SilkS")
		)
		(fp_line
			(start 0.7874 -0.4064)
			(end -0.7874 -0.4064)
			(stroke
				(width 0.1524)
				(type default)
			)
			(layer "B.SilkS")
		)
		(fp_line
			(start -0.7874 0.4064)
			(end 0.7874 0.4064)
			(stroke
				(width 0.1524)
				(type default)
			)
			(layer "B.SilkS")
		)
		(fp_line
			(start -0.7874 -0.4064)
			(end -0.7874 0.4064)
			(stroke
				(width 0.1524)
				(type default)
			)
			(layer "B.SilkS")
		)
		(fp_line
			(start 0.67945 0.3048)
			(end 0.67945 -0.305054)
			(stroke
				(width 0.1)
				(type default)
			)
			(layer "B.Fab")
		)
		(fp_line
			(start 0.67945 -0.305054)
			(end 0.12065 -0.305054)
			(stroke
				(width 0.1)
				(type default)
			)
			(layer "B.Fab")
		)
		(fp_line
			(start 0.12065 0.3048)
			(end 0.67945 0.3048)
			(stroke
				(width 0.1)
				(type default)
			)
			(layer "B.Fab")
		)
		(fp_line
			(start 0.12065 0.2794)
			(end 0.12065 0.3048)
			(stroke
				(width 0.1)
				(type default)
			)
			(layer "B.Fab")
		)
		(fp_line
			(start 0.12065 -0.2794)
			(end -0.12065 -0.2794)
			(stroke
				(width 0.1)
				(type default)
			)
			(layer "B.Fab")
		)
		(fp_line
			(start 0.12065 -0.305054)
			(end 0.12065 -0.2794)
			(stroke
				(width 0.1)
				(type default)
			)
			(layer "B.Fab")
		)
		(fp_line
			(start -0.120396 0.3048)
			(end -0.120396 0.2794)
			(stroke
				(width 0.1)
				(type default)
			)
			(layer "B.Fab")
		)
		(fp_line
			(start -0.120396 0.2794)
			(end 0.12065 0.2794)
			(stroke
				(width 0.1)
				(type default)
			)
			(layer "B.Fab")
		)
		(fp_line
			(start -0.12065 -0.2794)
			(end -0.12065 -0.3048)
			(stroke
				(width 0.1)
				(type default)
			)
			(layer "B.Fab")
		)
		(fp_line
			(start -0.12065 -0.3048)
			(end -0.67945 -0.3048)
			(stroke
				(width 0.1)
				(type default)
			)
			(layer "B.Fab")
		)
		(fp_line
			(start -0.67945 0.3048)
			(end -0.120396 0.3048)
			(stroke
				(width 0.1)
				(type default)
			)
			(layer "B.Fab")
		)
		(fp_line
			(start -0.67945 -0.3048)
			(end -0.67945 0.3048)
			(stroke
				(width 0.1)
				(type default)
			)
			(layer "B.Fab")
		)
		(pad "1" smd circle
			(at 0.40005 0)
			(size 0 0)
			(layers "B.Cu" "B.Mask" "B.Paste")
			(net "P3V3_AUX_CLK_GEN_VDDPT_CK440")
		)
		(pad "2" smd circle
			(at -0.40005 0)
			(size 0 0)
			(layers "B.Cu" "B.Mask" "B.Paste")
			(net "GND")
		)
	)
	(footprint ""
		(layer "B.Cu")
		(at 100.969572 -324.753986 -90)
		(property "Reference" "PC577_P1_2"
			(at 0 0 90)
			(layer "B.SilkS")
			(hide yes)
			(effects
				(font
					(size 1.27 1.27)
				)
				(justify mirror)
			)
		)
		(property "Value" ""
			(at 0 0 90)
			(layer "B.Fab")
			(effects
				(font
					(size 1.27 1.27)
				)
				(justify mirror)
			)
		)
		(duplicate_pad_numbers_are_jumpers no)
		(fp_line
			(start -1.524 0.762)
			(end 1.524 0.762)
			(stroke
				(width 0.1524)
				(type default)
			)
			(layer "B.SilkS")
		)
		(fp_line
			(start 1.524 0.762)
			(end 1.524 -0.762)
			(stroke
				(width 0.1524)
				(type default)
			)
			(layer "B.SilkS")
		)
		(fp_line
			(start -1.524 -0.762)
			(end -1.524 0.762)
			(stroke
				(width 0.1524)
				(type default)
			)
			(layer "B.SilkS")
		)
		(fp_line
			(start 1.524 -0.762)
			(end -1.524 -0.762)
			(stroke
				(width 0.1524)
				(type default)
			)
			(layer "B.SilkS")
		)
		(fp_line
			(start -1.1049 0.724916)
			(end -1.1049 -0.724916)
			(stroke
				(width 0.1)
				(type default)
			)
			(layer "B.Fab")
		)
		(fp_line
			(start 1.1049 0.724916)
			(end -1.1049 0.724916)
			(stroke
				(width 0.1)
				(type default)
			)
			(layer "B.Fab")
		)
		(fp_line
			(start -1.1049 -0.724916)
			(end 1.1049 -0.724916)
			(stroke
				(width 0.1)
				(type default)
			)
			(layer "B.Fab")
		)
		(fp_line
			(start 1.1049 -0.724916)
			(end 1.1049 0.724916)
			(stroke
				(width 0.1)
				(type default)
			)
			(layer "B.Fab")
		)
		(pad "1" smd rect
			(at 0.889 0 270)
			(size 1.016 1.27)
			(layers "B.Cu" "B.Mask" "B.Paste")
			(net "PVCCIN_CPU1")
		)
		(pad "2" smd rect
			(at -0.889 0 270)
			(size 1.016 1.27)
			(layers "B.Cu" "B.Mask" "B.Paste")
			(net "GND")
		)
	)
	(footprint ""
		(layer "B.Cu")
		(at 103.901494 -255.8542 90)
		(property "Reference" "C452"
			(at 0 0 90)
			(layer "B.SilkS")
			(hide yes)
			(effects
				(font
					(size 1.27 1.27)
				)
				(justify mirror)
			)
		)
		(property "Value" ""
			(at 0 0 90)
			(layer "B.Fab")
			(effects
				(font
					(size 1.27 1.27)
				)
				(justify mirror)
			)
		)
		(duplicate_pad_numbers_are_jumpers no)
		(fp_line
			(start 1.524 -0.762)
			(end -1.524 -0.762)
			(stroke
				(width 0.1524)
				(type default)
			)
			(layer "B.SilkS")
		)
		(fp_line
			(start -1.524 -0.762)
			(end -1.524 0.762)
			(stroke
				(width 0.1524)
				(type default)
			)
			(layer "B.SilkS")
		)
		(fp_line
			(start 1.524 0.762)
			(end 1.524 -0.762)
			(stroke
				(width 0.1524)
				(type default)
			)
			(layer "B.SilkS")
		)
		(fp_line
			(start -1.524 0.762)
			(end 1.524 0.762)
			(stroke
				(width 0.1524)
				(type default)
			)
			(layer "B.SilkS")
		)
		(fp_line
			(start 1.1049 -0.724916)
			(end 1.1049 0.724916)
			(stroke
				(width 0.1)
				(type default)
			)
			(layer "B.Fab")
		)
		(fp_line
			(start -1.1049 -0.724916)
			(end 1.1049 -0.724916)
			(stroke
				(width 0.1)
				(type default)
			)
			(layer "B.Fab")
		)
		(fp_line
			(start 1.1049 0.724916)
			(end -1.1049 0.724916)
			(stroke
				(width 0.1)
				(type default)
			)
			(layer "B.Fab")
		)
		(fp_line
			(start -1.1049 0.724916)
			(end -1.1049 -0.724916)
			(stroke
				(width 0.1)
				(type default)
			)
			(layer "B.Fab")
		)
		(pad "1" smd rect
			(at 0.889 0 90)
			(size 1.016 1.27)
			(layers "B.Cu" "B.Mask" "B.Paste")
			(net "PVCCFA_EHV_CPU1")
		)
		(pad "2" smd rect
			(at -0.889 0 90)
			(size 1.016 1.27)
			(layers "B.Cu" "B.Mask" "B.Paste")
			(net "GND")
		)
	)
	(footprint ""
		(layer "B.Cu")
		(at 418.570664 -183.327294 180)
		(property "Reference" "PR1777"
			(at 0 0 0)
			(layer "B.SilkS")
			(hide yes)
			(effects
				(font
					(size 1.27 1.27)
				)
				(justify mirror)
			)
		)
		(property "Value" ""
			(at 0 0 0)
			(layer "B.Fab")
			(effects
				(font
					(size 1.27 1.27)
				)
				(justify mirror)
			)
		)
		(duplicate_pad_numbers_are_jumpers no)
		(fp_line
			(start 0.7874 0.4064)
			(end 0.7874 -0.4064)
			(stroke
				(width 0.1524)
				(type default)
			)
			(layer "B.SilkS")
		)
		(fp_line
			(start 0.7874 -0.4064)
			(end -0.7874 -0.4064)
			(stroke
				(width 0.1524)
				(type default)
			)
			(layer "B.SilkS")
		)
		(fp_line
			(start -0.7874 0.4064)
			(end 0.7874 0.4064)
			(stroke
				(width 0.1524)
				(type default)
			)
			(layer "B.SilkS")
		)
		(fp_line
			(start -0.7874 -0.4064)
			(end -0.7874 0.4064)
			(stroke
				(width 0.1524)
				(type default)
			)
			(layer "B.SilkS")
		)
		(fp_line
			(start 0.67945 0.3048)
			(end 0.67945 -0.305054)
			(stroke
				(width 0.1)
				(type default)
			)
			(layer "B.Fab")
		)
		(fp_line
			(start 0.67945 -0.305054)
			(end 0.12065 -0.305054)
			(stroke
				(width 0.1)
				(type default)
			)
			(layer "B.Fab")
		)
		(fp_line
			(start 0.12065 0.3048)
			(end 0.67945 0.3048)
			(stroke
				(width 0.1)
				(type default)
			)
			(layer "B.Fab")
		)
		(fp_line
			(start 0.12065 0.2794)
			(end 0.12065 0.3048)
			(stroke
				(width 0.1)
				(type default)
			)
			(layer "B.Fab")
		)
		(fp_line
			(start 0.12065 -0.2794)
			(end -0.12065 -0.2794)
			(stroke
				(width 0.1)
				(type default)
			)
			(layer "B.Fab")
		)
		(fp_line
			(start 0.12065 -0.305054)
			(end 0.12065 -0.2794)
			(stroke
				(width 0.1)
				(type default)
			)
			(layer "B.Fab")
		)
		(fp_line
			(start -0.120396 0.3048)
			(end -0.120396 0.2794)
			(stroke
				(width 0.1)
				(type default)
			)
			(layer "B.Fab")
		)
		(fp_line
			(start -0.120396 0.2794)
			(end 0.12065 0.2794)
			(stroke
				(width 0.1)
				(type default)
			)
			(layer "B.Fab")
		)
		(fp_line
			(start -0.12065 -0.2794)
			(end -0.12065 -0.3048)
			(stroke
				(width 0.1)
				(type default)
			)
			(layer "B.Fab")
		)
		(fp_line
			(start -0.12065 -0.3048)
			(end -0.67945 -0.3048)
			(stroke
				(width 0.1)
				(type default)
			)
			(layer "B.Fab")
		)
		(fp_line
			(start -0.67945 0.3048)
			(end -0.120396 0.3048)
			(stroke
				(width 0.1)
				(type default)
			)
			(layer "B.Fab")
		)
		(fp_line
			(start -0.67945 -0.3048)
			(end -0.67945 0.3048)
			(stroke
				(width 0.1)
				(type default)
			)
			(layer "B.Fab")
		)
		(pad "1" smd circle
			(at 0.40005 0)
			(size 0 0)
			(layers "B.Cu" "B.Mask" "B.Paste")
			(net "PVCCINFAON_CPU0_VOS2")
		)
		(pad "2" smd circle
			(at -0.40005 0)
			(size 0 0)
			(layers "B.Cu" "B.Mask" "B.Paste")
			(net "PVCCINFAON_CPU0")
		)
	)
	(footprint ""
		(layer "B.Cu")
		(at 446.780158 -177.78476 180)
		(property "Reference" "C1400"
			(at 0 0 0)
			(layer "B.SilkS")
			(hide yes)
			(effects
				(font
					(size 1.27 1.27)
				)
				(justify mirror)
			)
		)
		(property "Value" ""
			(at 0 0 0)
			(layer "B.Fab")
			(effects
				(font
					(size 1.27 1.27)
				)
				(justify mirror)
			)
		)
		(duplicate_pad_numbers_are_jumpers no)
		(fp_line
			(start 1.524 0.762)
			(end 1.524 -0.762)
			(stroke
				(width 0.1524)
				(type default)
			)
			(layer "B.SilkS")
		)
		(fp_line
			(start 1.524 -0.762)
			(end -1.524 -0.762)
			(stroke
				(width 0.1524)
				(type default)
			)
			(layer "B.SilkS")
		)
		(fp_line
			(start -1.524 0.762)
			(end 1.524 0.762)
			(stroke
				(width 0.1524)
				(type default)
			)
			(layer "B.SilkS")
		)
		(fp_line
			(start -1.524 -0.762)
			(end -1.524 0.762)
			(stroke
				(width 0.1524)
				(type default)
			)
			(layer "B.SilkS")
		)
		(fp_line
			(start 1.1049 0.724916)
			(end -1.1049 0.724916)
			(stroke
				(width 0.1)
				(type default)
			)
			(layer "B.Fab")
		)
		(fp_line
			(start 1.1049 -0.724916)
			(end 1.1049 0.724916)
			(stroke
				(width 0.1)
				(type default)
			)
			(layer "B.Fab")
		)
		(fp_line
			(start -1.1049 0.724916)
			(end -1.1049 -0.724916)
			(stroke
				(width 0.1)
				(type default)
			)
			(layer "B.Fab")
		)
		(fp_line
			(start -1.1049 -0.724916)
			(end 1.1049 -0.724916)
			(stroke
				(width 0.1)
				(type default)
			)
			(layer "B.Fab")
		)
		(pad "1" smd rect
			(at 0.889 0 180)
			(size 1.016 1.27)
			(layers "B.Cu" "B.Mask" "B.Paste")
			(net "PVNN_MAIN_CPU0")
		)
		(pad "2" smd rect
			(at -0.889 0 180)
			(size 1.016 1.27)
			(layers "B.Cu" "B.Mask" "B.Paste")
			(net "GND")
		)
	)
	(footprint ""
		(layer "B.Cu")
		(at 416.996626 -173.218602 180)
		(property "Reference" "PR101"
			(at 0 0 0)
			(layer "B.SilkS")
			(hide yes)
			(effects
				(font
					(size 1.27 1.27)
				)
				(justify mirror)
			)
		)
		(property "Value" ""
			(at 0 0 0)
			(layer "B.Fab")
			(effects
				(font
					(size 1.27 1.27)
				)
				(justify mirror)
			)
		)
		(duplicate_pad_numbers_are_jumpers no)
		(fp_line
			(start 0.7874 0.4064)
			(end 0.7874 -0.4064)
			(stroke
				(width 0.1524)
				(type default)
			)
			(layer "B.SilkS")
		)
		(fp_line
			(start 0.7874 -0.4064)
			(end -0.7874 -0.4064)
			(stroke
				(width 0.1524)
				(type default)
			)
			(layer "B.SilkS")
		)
		(fp_line
			(start -0.7874 0.4064)
			(end 0.7874 0.4064)
			(stroke
				(width 0.1524)
				(type default)
			)
			(layer "B.SilkS")
		)
		(fp_line
			(start -0.7874 -0.4064)
			(end -0.7874 0.4064)
			(stroke
				(width 0.1524)
				(type default)
			)
			(layer "B.SilkS")
		)
		(fp_line
			(start 0.67945 0.3048)
			(end 0.67945 -0.305054)
			(stroke
				(width 0.1)
				(type default)
			)
			(layer "B.Fab")
		)
		(fp_line
			(start 0.67945 -0.305054)
			(end 0.12065 -0.305054)
			(stroke
				(width 0.1)
				(type default)
			)
			(layer "B.Fab")
		)
		(fp_line
			(start 0.12065 0.3048)
			(end 0.67945 0.3048)
			(stroke
				(width 0.1)
				(type default)
			)
			(layer "B.Fab")
		)
		(fp_line
			(start 0.12065 0.2794)
			(end 0.12065 0.3048)
			(stroke
				(width 0.1)
				(type default)
			)
			(layer "B.Fab")
		)
		(fp_line
			(start 0.12065 -0.2794)
			(end -0.12065 -0.2794)
			(stroke
				(width 0.1)
				(type default)
			)
			(layer "B.Fab")
		)
		(fp_line
			(start 0.12065 -0.305054)
			(end 0.12065 -0.2794)
			(stroke
				(width 0.1)
				(type default)
			)
			(layer "B.Fab")
		)
		(fp_line
			(start -0.120396 0.3048)
			(end -0.120396 0.2794)
			(stroke
				(width 0.1)
				(type default)
			)
			(layer "B.Fab")
		)
		(fp_line
			(start -0.120396 0.2794)
			(end 0.12065 0.2794)
			(stroke
				(width 0.1)
				(type default)
			)
			(layer "B.Fab")
		)
		(fp_line
			(start -0.12065 -0.2794)
			(end -0.12065 -0.3048)
			(stroke
				(width 0.1)
				(type default)
			)
			(layer "B.Fab")
		)
		(fp_line
			(start -0.12065 -0.3048)
			(end -0.67945 -0.3048)
			(stroke
				(width 0.1)
				(type default)
			)
			(layer "B.Fab")
		)
		(fp_line
			(start -0.67945 0.3048)
			(end -0.120396 0.3048)
			(stroke
				(width 0.1)
				(type default)
			)
			(layer "B.Fab")
		)
		(fp_line
			(start -0.67945 -0.3048)
			(end -0.67945 0.3048)
			(stroke
				(width 0.1)
				(type default)
			)
			(layer "B.Fab")
		)
		(pad "1" smd circle
			(at 0.40005 0)
			(size 0 0)
			(layers "B.Cu" "B.Mask" "B.Paste")
			(net "PVCCFA_EHV_CPU0_PVCC")
		)
		(pad "2" smd circle
			(at -0.40005 0)
			(size 0 0)
			(layers "B.Cu" "B.Mask" "B.Paste")
			(net "PVCCINFAON_CPU0_VDD1")
		)
	)
	(footprint ""
		(layer "B.Cu")
		(at 317.632588 -35.856672 -135)
		(property "Reference" "R4674"
			(at 0 0 45)
			(layer "B.SilkS")
			(hide yes)
			(effects
				(font
					(size 1.27 1.27)
				)
				(justify mirror)
			)
		)
		(property "Value" ""
			(at 0 0 45)
			(layer "B.Fab")
			(effects
				(font
					(size 1.27 1.27)
				)
				(justify mirror)
			)
		)
		(duplicate_pad_numbers_are_jumpers no)
		(fp_line
			(start 0.787389 0.406267)
			(end 0.787389 -0.406267)
			(stroke
				(width 0.1524)
				(type default)
			)
			(layer "B.SilkS")
		)
		(fp_line
			(start 0.787389 -0.406267)
			(end -0.787389 -0.406267)
			(stroke
				(width 0.1524)
				(type default)
			)
			(layer "B.SilkS")
		)
		(fp_line
			(start -0.787389 0.406267)
			(end 0.787389 0.406267)
			(stroke
				(width 0.1524)
				(type default)
			)
			(layer "B.SilkS")
		)
		(fp_line
			(start -0.787389 -0.406267)
			(end -0.787389 0.406267)
			(stroke
				(width 0.1524)
				(type default)
			)
			(layer "B.SilkS")
		)
		(fp_line
			(start 0.679446 0.30479)
			(end 0.679446 -0.305149)
			(stroke
				(width 0.1)
				(type default)
			)
			(layer "B.Fab")
		)
		(fp_line
			(start 0.120515 0.30479)
			(end 0.679446 0.30479)
			(stroke
				(width 0.1)
				(type default)
			)
			(layer "B.Fab")
		)
		(fp_line
			(start 0.120695 0.279466)
			(end 0.120515 0.30479)
			(stroke
				(width 0.1)
				(type default)
			)
			(layer "B.Fab")
		)
		(fp_line
			(start 0.679446 -0.305149)
			(end 0.120695 -0.304969)
			(stroke
				(width 0.1)
				(type default)
			)
			(layer "B.Fab")
		)
		(fp_line
			(start -0.120515 0.30479)
			(end -0.120335 0.279466)
			(stroke
				(width 0.1)
				(type default)
			)
			(layer "B.Fab")
		)
		(fp_line
			(start -0.120335 0.279466)
			(end 0.120695 0.279466)
			(stroke
				(width 0.1)
				(type default)
			)
			(layer "B.Fab")
		)
		(fp_line
			(start 0.120695 -0.279466)
			(end -0.120695 -0.279466)
			(stroke
				(width 0.1)
				(type default)
			)
			(layer "B.Fab")
		)
		(fp_line
			(start 0.120695 -0.304969)
			(end 0.120695 -0.279466)
			(stroke
				(width 0.1)
				(type default)
			)
			(layer "B.Fab")
		)
		(fp_line
			(start -0.679446 0.30479)
			(end -0.120515 0.30479)
			(stroke
				(width 0.1)
				(type default)
			)
			(layer "B.Fab")
		)
		(fp_line
			(start -0.120695 -0.279466)
			(end -0.120515 -0.30479)
			(stroke
				(width 0.1)
				(type default)
			)
			(layer "B.Fab")
		)
		(fp_line
			(start -0.120515 -0.30479)
			(end -0.679446 -0.30479)
			(stroke
				(width 0.1)
				(type default)
			)
			(layer "B.Fab")
		)
		(fp_line
			(start -0.679446 -0.30479)
			(end -0.679446 0.30479)
			(stroke
				(width 0.1)
				(type default)
			)
			(layer "B.Fab")
		)
		(pad "1" smd circle
			(at 0.40005 0 45)
			(size 0 0)
			(layers "B.Cu" "B.Mask" "B.Paste")
			(net "FM_SLP_SUS_RSM_RST_N")
		)
		(pad "2" smd circle
			(at -0.40005 0 45)
			(size 0 0)
			(layers "B.Cu" "B.Mask" "B.Paste")
			(net "GND")
		)
	)
)
